# T6G (Grand Teton) — schematic netlist excerpt (pin names and nets, part order shuffled) for the footprints in the layout excerpt that follows; sources: Cadence DE-HDL packaged netlist, KiCad conversion of 04192023_DAF0TMB3IC0_F0TG_MB_C_brd_V02_OCP.brd

R2426  Q_RES  100 1% EMPTY  pkg 0402LF  page 145 : A = E1S_0_PERST1_CLKREQ_N ; B = GND
R129  Q_RES  1K 1% EMPTY  pkg 0402LF  page 77 : A = P3V3_AUX ; B = SPI_CPU0_LVC3_SCM_D3
C1532  Q_CAP_DIFFBUS  DIFF BUS_0.22UF 6.3V 20% X6S  pkg C0201  page 67 : \1\ = P5E_CPU1_P3_TX_C_DN<7> ; \2\ = P5E_CPU1_P3_TX_DN<7>

(kicad_pcb
	(version 20260206)
	(generator "pcbnew")
	(generator_version "10.0")
	(general
		(thickness 1.6)
		(legacy_teardrops no)
	)
	(paper "A4")
	(title_block
		(title "04192023_DAF0TMB3IC0_F0TG_MB_C_brd_V02_OCP.brd")
		(comment 1 "Grand Teton / footprints 3256-3258 of 8354")
	)
	(layers
		(0 "F.Cu" signal "TOP")
		(4 "In1.Cu" signal "GND")
		(6 "In2.Cu" signal "IN1")
		(8 "In3.Cu" signal "GND1")
		(10 "In4.Cu" signal "IN2")
		(12 "In5.Cu" signal "GND2")
		(14 "In6.Cu" signal "IN3")
		(16 "In7.Cu" signal "GND3")
		(18 "In8.Cu" signal "VCC")
		(20 "In9.Cu" signal "VCC1")
		(22 "In10.Cu" signal "GND4")
		(24 "In11.Cu" signal "IN4")
		(26 "In12.Cu" signal "GND5")
		(28 "In13.Cu" signal "IN5")
		(30 "In14.Cu" signal "GND6")
		(32 "In15.Cu" signal "IN6")
		(34 "In16.Cu" signal "GND7")
		(2 "B.Cu" signal "BOTTOM")
		(9 "F.Adhes" user "F.Adhesive")
		(11 "B.Adhes" user "B.Adhesive")
		(13 "F.Paste" user "Package Geometry/Pastemask Top")
		(15 "B.Paste" user "Package Geometry/Pastemask Bottom")
		(5 "F.SilkS" user "Ref Des/Silkscreen Top")
		(7 "B.SilkS" user "Ref Des/Silkscreen Bottom")
		(1 "F.Mask" user "Board Geometry/Soldermask Top")
		(3 "B.Mask" user "Board Geometry/Soldermask Bottom")
		(17 "Dwgs.User" user "User.Drawings")
		(19 "Cmts.User" user "User.Comments")
		(21 "Eco1.User" user "User.Eco1")
		(23 "Eco2.User" user "User.Eco2")
		(25 "Edge.Cuts" user "Board Geometry/Outline")
		(27 "Margin" user)
		(31 "F.CrtYd" user "Package Geometry/Place Bound Top")
		(29 "B.CrtYd" user "Package Geometry/Place Bound Bottom")
		(35 "F.Fab" user "Ref Des/Assembly Top")
		(33 "B.Fab" user "Ref Des/Assembly Bottom")
	)
	(footprint ""
		(layer "F.Cu")
		(at 255.780794 -138.048746 90)
		(property "Reference" "R129"
			(at 0 0 90)
			(layer "F.SilkS")
			(hide yes)
			(effects
				(font
					(size 1.27 1.27)
				)
			)
		)
		(property "Value" ""
			(at 0 0 90)
			(layer "F.Fab")
			(effects
				(font
					(size 1.27 1.27)
				)
			)
		)
		(duplicate_pad_numbers_are_jumpers no)
		(fp_line
			(start 0.7874 -0.4064)
			(end 0.7874 0.4064)
			(stroke
				(width 0.1524)
				(type default)
			)
			(layer "F.SilkS")
		)
		(fp_line
			(start -0.7874 -0.4064)
			(end 0.7874 -0.4064)
			(stroke
				(width 0.1524)
				(type default)
			)
			(layer "F.SilkS")
		)
		(fp_line
			(start 0.7874 0.4064)
			(end -0.7874 0.4064)
			(stroke
				(width 0.1524)
				(type default)
			)
			(layer "F.SilkS")
		)
		(fp_line
			(start -0.7874 0.4064)
			(end -0.7874 -0.4064)
			(stroke
				(width 0.1524)
				(type default)
			)
			(layer "F.SilkS")
		)
		(fp_line
			(start -0.12065 -0.305054)
			(end -0.12065 -0.2794)
			(stroke
				(width 0.1)
				(type default)
			)
			(layer "F.Fab")
		)
		(fp_line
			(start -0.67945 -0.305054)
			(end -0.12065 -0.305054)
			(stroke
				(width 0.1)
				(type default)
			)
			(layer "F.Fab")
		)
		(fp_line
			(start 0.67945 -0.3048)
			(end 0.67945 0.3048)
			(stroke
				(width 0.1)
				(type default)
			)
			(layer "F.Fab")
		)
		(fp_line
			(start 0.12065 -0.3048)
			(end 0.67945 -0.3048)
			(stroke
				(width 0.1)
				(type default)
			)
			(layer "F.Fab")
		)
		(fp_line
			(start 0.12065 -0.2794)
			(end 0.12065 -0.3048)
			(stroke
				(width 0.1)
				(type default)
			)
			(layer "F.Fab")
		)
		(fp_line
			(start -0.12065 -0.2794)
			(end 0.12065 -0.2794)
			(stroke
				(width 0.1)
				(type default)
			)
			(layer "F.Fab")
		)
		(fp_line
			(start 0.120396 0.2794)
			(end -0.12065 0.2794)
			(stroke
				(width 0.1)
				(type default)
			)
			(layer "F.Fab")
		)
		(fp_line
			(start -0.12065 0.2794)
			(end -0.12065 0.3048)
			(stroke
				(width 0.1)
				(type default)
			)
			(layer "F.Fab")
		)
		(fp_line
			(start 0.67945 0.3048)
			(end 0.120396 0.3048)
			(stroke
				(width 0.1)
				(type default)
			)
			(layer "F.Fab")
		)
		(fp_line
			(start 0.120396 0.3048)
			(end 0.120396 0.2794)
			(stroke
				(width 0.1)
				(type default)
			)
			(layer "F.Fab")
		)
		(fp_line
			(start -0.12065 0.3048)
			(end -0.67945 0.3048)
			(stroke
				(width 0.1)
				(type default)
			)
			(layer "F.Fab")
		)
		(fp_line
			(start -0.67945 0.3048)
			(end -0.67945 -0.305054)
			(stroke
				(width 0.1)
				(type default)
			)
			(layer "F.Fab")
		)
		(pad "1" smd circle
			(at -0.40005 0 90)
			(size 0 0)
			(layers "F.Cu" "F.Mask" "F.Paste")
			(net "P3V3_AUX")
		)
		(pad "2" smd circle
			(at 0.40005 0 90)
			(size 0 0)
			(layers "F.Cu" "F.Mask" "F.Paste")
			(net "SPI_CPU0_LVC3_SCM_D3")
		)
	)
	(footprint ""
		(layer "F.Cu")
		(at 122.916696 -375.49963 -90)
		(property "Reference" "C1532"
			(at 0 0 270)
			(layer "F.SilkS")
			(hide yes)
			(effects
				(font
					(size 1.27 1.27)
				)
			)
		)
		(property "Value" ""
			(at 0 0 270)
			(layer "F.Fab")
			(effects
				(font
					(size 1.27 1.27)
				)
			)
		)
		(duplicate_pad_numbers_are_jumpers no)
		(fp_line
			(start -0.299974 0.150114)
			(end -0.299974 -0.150114)
			(stroke
				(width 0.1)
				(type default)
			)
			(layer "F.Fab")
		)
		(fp_line
			(start 0.299974 0.150114)
			(end -0.299974 0.150114)
			(stroke
				(width 0.1)
				(type default)
			)
			(layer "F.Fab")
		)
		(fp_line
			(start -0.299974 -0.150114)
			(end 0.299974 -0.150114)
			(stroke
				(width 0.1)
				(type default)
			)
			(layer "F.Fab")
		)
		(fp_line
			(start 0.299974 -0.150114)
			(end 0.299974 0.150114)
			(stroke
				(width 0.1)
				(type default)
			)
			(layer "F.Fab")
		)
		(pad "1" smd rect
			(at -0.2667 0 270)
			(size 0.3048 0.381)
			(layers "F.Cu" "F.Mask" "F.Paste")
			(net "P5E_CPU1_P3_TX_C_DN<7>")
		)
		(pad "2" smd rect
			(at 0.2667 0 270)
			(size 0.3048 0.381)
			(layers "F.Cu" "F.Mask" "F.Paste")
			(net "P5E_CPU1_P3_TX_DN<7>")
		)
	)
	(footprint ""
		(layer "F.Cu")
		(at 224.21215 -48.78197 180)
		(property "Reference" "R2426"
			(at 0 0 180)
			(layer "F.SilkS")
			(hide yes)
			(effects
				(font
					(size 1.27 1.27)
				)
			)
		)
		(property "Value" ""
			(at 0 0 180)
			(layer "F.Fab")
			(effects
				(font
					(size 1.27 1.27)
				)
			)
		)
		(duplicate_pad_numbers_are_jumpers no)
		(fp_line
			(start 0.7874 0.4064)
			(end -0.7874 0.4064)
			(stroke
				(width 0.1524)
				(type default)
			)
			(layer "F.SilkS")
		)
		(fp_line
			(start 0.7874 -0.4064)
			(end 0.7874 0.4064)
			(stroke
				(width 0.1524)
				(type default)
			)
			(layer "F.SilkS")
		)
		(fp_line
			(start -0.7874 0.4064)
			(end -0.7874 -0.4064)
			(stroke
				(width 0.1524)
				(type default)
			)
			(layer "F.SilkS")
		)
		(fp_line
			(start -0.7874 -0.4064)
			(end 0.7874 -0.4064)
			(stroke
				(width 0.1524)
				(type default)
			)
			(layer "F.SilkS")
		)
		(fp_line
			(start 0.67945 0.3048)
			(end 0.120396 0.3048)
			(stroke
				(width 0.1)
				(type default)
			)
			(layer "F.Fab")
		)
		(fp_line
			(start 0.67945 -0.3048)
			(end 0.67945 0.3048)
			(stroke
				(width 0.1)
				(type default)
			)
			(layer "F.Fab")
		)
		(fp_line
			(start 0.12065 -0.2794)
			(end 0.12065 -0.3048)
			(stroke
				(width 0.1)
				(type default)
			)
			(layer "F.Fab")
		)
		(fp_line
			(start 0.12065 -0.3048)
			(end 0.67945 -0.3048)
			(stroke
				(width 0.1)
				(type default)
			)
			(layer "F.Fab")
		)
		(fp_line
			(start 0.120396 0.3048)
			(end 0.120396 0.2794)
			(stroke
				(width 0.1)
				(type default)
			)
			(layer "F.Fab")
		)
		(fp_line
			(start 0.120396 0.2794)
			(end -0.12065 0.2794)
			(stroke
				(width 0.1)
				(type default)
			)
			(layer "F.Fab")
		)
		(fp_line
			(start -0.12065 0.3048)
			(end -0.67945 0.3048)
			(stroke
				(width 0.1)
				(type default)
			)
			(layer "F.Fab")
		)
		(fp_line
			(start -0.12065 0.2794)
			(end -0.12065 0.3048)
			(stroke
				(width 0.1)
				(type default)
			)
			(layer "F.Fab")
		)
		(fp_line
			(start -0.12065 -0.2794)
			(end 0.12065 -0.2794)
			(stroke
				(width 0.1)
				(type default)
			)
			(layer "F.Fab")
		)
		(fp_line
			(start -0.12065 -0.305054)
			(end -0.12065 -0.2794)
			(stroke
				(width 0.1)
				(type default)
			)
			(layer "F.Fab")
		)
		(fp_line
			(start -0.67945 0.3048)
			(end -0.67945 -0.305054)
			(stroke
				(width 0.1)
				(type default)
			)
			(layer "F.Fab")
		)
		(fp_line
			(start -0.67945 -0.305054)
			(end -0.12065 -0.305054)
			(stroke
				(width 0.1)
				(type default)
			)
			(layer "F.Fab")
		)
		(pad "1" smd circle
			(at -0.40005 0 180)
			(size 0 0)
			(layers "F.Cu" "F.Mask" "F.Paste")
			(net "E1S_0_PERST1_CLKREQ_N")
		)
		(pad "2" smd circle
			(at 0.40005 0 180)
			(size 0 0)
			(layers "F.Cu" "F.Mask" "F.Paste")
			(net "GND")
		)
	)
)
